(kicad_pcb
	(version 20260206)
	(generator "pcbnew")
	(generator_version "10.0")
	(general
		(thickness 1.6)
		(legacy_teardrops no)
	)
	(paper "A4")
	(title_block
		(title "01162023_DA0F0TEBIF0_F0T_Expander_BD_F_brd_V02_OCP.brd")
		(comment 1 "Grand Teton / footprints 6026-6032 of 9728")
	)
	(layers
		(0 "F.Cu" signal "TOP")
		(4 "In1.Cu" signal "GND")
		(6 "In2.Cu" signal "VCC")
		(8 "In3.Cu" signal "VCC1")
		(10 "In4.Cu" signal "GND1")
		(12 "In5.Cu" signal "IN1")
		(14 "In6.Cu" signal "GND2")
		(16 "In7.Cu" signal "IN2")
		(18 "In8.Cu" signal "GND3")
		(20 "In9.Cu" signal "IN3")
		(22 "In10.Cu" signal "GND4")
		(24 "In11.Cu" signal "IN4")
		(26 "In12.Cu" signal "GND5")
		(28 "In13.Cu" signal "IN5")
		(30 "In14.Cu" signal "GND6")
		(32 "In15.Cu" signal "IN6")
		(34 "In16.Cu" signal "GND7")
		(2 "B.Cu" signal "BOTTOM")
		(9 "F.Adhes" user "F.Adhesive")
		(11 "B.Adhes" user "B.Adhesive")
		(13 "F.Paste" user "Package Geometry/Pastemask Top")
		(15 "B.Paste" user "Package Geometry/Pastemask Bottom")
		(5 "F.SilkS" user "Ref Des/Silkscreen Top")
		(7 "B.SilkS" user "Ref Des/Silkscreen Bottom")
		(1 "F.Mask" user "Board Geometry/Soldermask Top")
		(3 "B.Mask" user "Board Geometry/Soldermask Bottom")
		(17 "Dwgs.User" user "User.Drawings")
		(19 "Cmts.User" user "User.Comments")
		(21 "Eco1.User" user "User.Eco1")
		(23 "Eco2.User" user "User.Eco2")
		(25 "Edge.Cuts" user "Board Geometry/Outline")
		(27 "Margin" user)
		(31 "F.CrtYd" user "Package Geometry/Place Bound Top")
		(29 "B.CrtYd" user "Package Geometry/Place Bound Bottom")
		(35 "F.Fab" user "Ref Des/Assembly Top")
		(33 "B.Fab" user "Ref Des/Assembly Bottom")
	)
	(footprint ""
		(layer "F.Cu")
		(at 86.72957 -300.62043 90)
		(property "Reference" "R6386"
			(at 0 0 90)
			(layer "F.SilkS")
			(hide yes)
			(effects
				(font
					(size 1.27 1.27)
				)
			)
		)
		(property "Value" ""
			(at 0 0 90)
			(layer "F.Fab")
			(effects
				(font
					(size 1.27 1.27)
				)
			)
		)
		(duplicate_pad_numbers_are_jumpers no)
		(fp_line
			(start 0.7874 -0.4064)
			(end 0.7874 0.4064)
			(stroke
				(width 0.1524)
				(type default)
			)
			(layer "F.SilkS")
		)
		(fp_line
			(start -0.7874 -0.4064)
			(end 0.7874 -0.4064)
			(stroke
				(width 0.1524)
				(type default)
			)
			(layer "F.SilkS")
		)
		(fp_line
			(start 0.7874 0.4064)
			(end -0.7874 0.4064)
			(stroke
				(width 0.1524)
				(type default)
			)
			(layer "F.SilkS")
		)
		(fp_line
			(start -0.7874 0.4064)
			(end -0.7874 -0.4064)
			(stroke
				(width 0.1524)
				(type default)
			)
			(layer "F.SilkS")
		)
		(fp_line
			(start -0.12065 -0.305054)
			(end -0.12065 -0.2794)
			(stroke
				(width 0.1)
				(type default)
			)
			(layer "F.Fab")
		)
		(fp_line
			(start -0.67945 -0.305054)
			(end -0.12065 -0.305054)
			(stroke
				(width 0.1)
				(type default)
			)
			(layer "F.Fab")
		)
		(fp_line
			(start 0.67945 -0.3048)
			(end 0.67945 0.3048)
			(stroke
				(width 0.1)
				(type default)
			)
			(layer "F.Fab")
		)
		(fp_line
			(start 0.12065 -0.3048)
			(end 0.67945 -0.3048)
			(stroke
				(width 0.1)
				(type default)
			)
			(layer "F.Fab")
		)
		(fp_line
			(start 0.12065 -0.2794)
			(end 0.12065 -0.3048)
			(stroke
				(width 0.1)
				(type default)
			)
			(layer "F.Fab")
		)
		(fp_line
			(start -0.12065 -0.2794)
			(end 0.12065 -0.2794)
			(stroke
				(width 0.1)
				(type default)
			)
			(layer "F.Fab")
		)
		(fp_line
			(start 0.120396 0.2794)
			(end -0.12065 0.2794)
			(stroke
				(width 0.1)
				(type default)
			)
			(layer "F.Fab")
		)
		(fp_line
			(start -0.12065 0.2794)
			(end -0.12065 0.3048)
			(stroke
				(width 0.1)
				(type default)
			)
			(layer "F.Fab")
		)
		(fp_line
			(start 0.67945 0.3048)
			(end 0.120396 0.3048)
			(stroke
				(width 0.1)
				(type default)
			)
			(layer "F.Fab")
		)
		(fp_line
			(start 0.120396 0.3048)
			(end 0.120396 0.2794)
			(stroke
				(width 0.1)
				(type default)
			)
			(layer "F.Fab")
		)
		(fp_line
			(start -0.12065 0.3048)
			(end -0.67945 0.3048)
			(stroke
				(width 0.1)
				(type default)
			)
			(layer "F.Fab")
		)
		(fp_line
			(start -0.67945 0.3048)
			(end -0.67945 -0.305054)
			(stroke
				(width 0.1)
				(type default)
			)
			(layer "F.Fab")
		)
		(pad "1" smd circle
			(at -0.40005 0 90)
			(size 0 0)
			(layers "F.Cu" "F.Mask" "F.Paste")
			(net "RST_PEX0_S3_PERST_N")
		)
		(pad "2" smd circle
			(at 0.40005 0 90)
			(size 0 0)
			(layers "F.Cu" "F.Mask" "F.Paste")
			(net "RST_PEX0_S3_PERST_R_N")
		)
	)
	(footprint ""
		(layer "F.Cu")
		(at 236.706664 -206.51216 90)
		(property "Reference" "R3286"
			(at 0 0 90)
			(layer "F.SilkS")
			(hide yes)
			(effects
				(font
					(size 1.27 1.27)
				)
			)
		)
		(property "Value" ""
			(at 0 0 90)
			(layer "F.Fab")
			(effects
				(font
					(size 1.27 1.27)
				)
			)
		)
		(duplicate_pad_numbers_are_jumpers no)
		(fp_line
			(start 0.7874 -0.4064)
			(end 0.7874 0.4064)
			(stroke
				(width 0.1524)
				(type default)
			)
			(layer "F.SilkS")
		)
		(fp_line
			(start -0.7874 -0.4064)
			(end 0.7874 -0.4064)
			(stroke
				(width 0.1524)
				(type default)
			)
			(layer "F.SilkS")
		)
		(fp_line
			(start 0.7874 0.4064)
			(end -0.7874 0.4064)
			(stroke
				(width 0.1524)
				(type default)
			)
			(layer "F.SilkS")
		)
		(fp_line
			(start -0.7874 0.4064)
			(end -0.7874 -0.4064)
			(stroke
				(width 0.1524)
				(type default)
			)
			(layer "F.SilkS")
		)
		(fp_line
			(start -0.12065 -0.305054)
			(end -0.12065 -0.2794)
			(stroke
				(width 0.1)
				(type default)
			)
			(layer "F.Fab")
		)
		(fp_line
			(start -0.67945 -0.305054)
			(end -0.12065 -0.305054)
			(stroke
				(width 0.1)
				(type default)
			)
			(layer "F.Fab")
		)
		(fp_line
			(start 0.67945 -0.3048)
			(end 0.67945 0.3048)
			(stroke
				(width 0.1)
				(type default)
			)
			(layer "F.Fab")
		)
		(fp_line
			(start 0.12065 -0.3048)
			(end 0.67945 -0.3048)
			(stroke
				(width 0.1)
				(type default)
			)
			(layer "F.Fab")
		)
		(fp_line
			(start 0.12065 -0.2794)
			(end 0.12065 -0.3048)
			(stroke
				(width 0.1)
				(type default)
			)
			(layer "F.Fab")
		)
		(fp_line
			(start -0.12065 -0.2794)
			(end 0.12065 -0.2794)
			(stroke
				(width 0.1)
				(type default)
			)
			(layer "F.Fab")
		)
		(fp_line
			(start 0.120396 0.2794)
			(end -0.12065 0.2794)
			(stroke
				(width 0.1)
				(type default)
			)
			(layer "F.Fab")
		)
		(fp_line
			(start -0.12065 0.2794)
			(end -0.12065 0.3048)
			(stroke
				(width 0.1)
				(type default)
			)
			(layer "F.Fab")
		)
		(fp_line
			(start 0.67945 0.3048)
			(end 0.120396 0.3048)
			(stroke
				(width 0.1)
				(type default)
			)
			(layer "F.Fab")
		)
		(fp_line
			(start 0.120396 0.3048)
			(end 0.120396 0.2794)
			(stroke
				(width 0.1)
				(type default)
			)
			(layer "F.Fab")
		)
		(fp_line
			(start -0.12065 0.3048)
			(end -0.67945 0.3048)
			(stroke
				(width 0.1)
				(type default)
			)
			(layer "F.Fab")
		)
		(fp_line
			(start -0.67945 0.3048)
			(end -0.67945 -0.305054)
			(stroke
				(width 0.1)
				(type default)
			)
			(layer "F.Fab")
		)
		(pad "1" smd circle
			(at -0.40005 0 90)
			(size 0 0)
			(layers "F.Cu" "F.Mask" "F.Paste")
			(net "BIC_HEARTBEAT_N")
		)
		(pad "2" smd circle
			(at 0.40005 0 90)
			(size 0 0)
			(layers "F.Cu" "F.Mask" "F.Paste")
			(net "P3V3_AUX")
		)
	)
	(footprint ""
		(layer "F.Cu")
		(at 268.734286 -252.356874 -90)
		(property "Reference" "R1362"
			(at 0 0 270)
			(layer "F.SilkS")
			(hide yes)
			(effects
				(font
					(size 1.27 1.27)
				)
			)
		)
		(property "Value" ""
			(at 0 0 270)
			(layer "F.Fab")
			(effects
				(font
					(size 1.27 1.27)
				)
			)
		)
		(duplicate_pad_numbers_are_jumpers no)
		(fp_line
			(start -0.7874 0.4064)
			(end -0.7874 -0.4064)
			(stroke
				(width 0.1524)
				(type default)
			)
			(layer "F.SilkS")
		)
		(fp_line
			(start 0.7874 0.4064)
			(end -0.7874 0.4064)
			(stroke
				(width 0.1524)
				(type default)
			)
			(layer "F.SilkS")
		)
		(fp_line
			(start -0.7874 -0.4064)
			(end 0.7874 -0.4064)
			(stroke
				(width 0.1524)
				(type default)
			)
			(layer "F.SilkS")
		)
		(fp_line
			(start 0.7874 -0.4064)
			(end 0.7874 0.4064)
			(stroke
				(width 0.1524)
				(type default)
			)
			(layer "F.SilkS")
		)
		(fp_line
			(start -0.67945 0.3048)
			(end -0.67945 -0.305054)
			(stroke
				(width 0.1)
				(type default)
			)
			(layer "F.Fab")
		)
		(fp_line
			(start -0.12065 0.3048)
			(end -0.67945 0.3048)
			(stroke
				(width 0.1)
				(type default)
			)
			(layer "F.Fab")
		)
		(fp_line
			(start 0.120396 0.3048)
			(end 0.120396 0.2794)
			(stroke
				(width 0.1)
				(type default)
			)
			(layer "F.Fab")
		)
		(fp_line
			(start 0.67945 0.3048)
			(end 0.120396 0.3048)
			(stroke
				(width 0.1)
				(type default)
			)
			(layer "F.Fab")
		)
		(fp_line
			(start -0.12065 0.2794)
			(end -0.12065 0.3048)
			(stroke
				(width 0.1)
				(type default)
			)
			(layer "F.Fab")
		)
		(fp_line
			(start 0.120396 0.2794)
			(end -0.12065 0.2794)
			(stroke
				(width 0.1)
				(type default)
			)
			(layer "F.Fab")
		)
		(fp_line
			(start -0.12065 -0.2794)
			(end 0.12065 -0.2794)
			(stroke
				(width 0.1)
				(type default)
			)
			(layer "F.Fab")
		)
		(fp_line
			(start 0.12065 -0.2794)
			(end 0.12065 -0.3048)
			(stroke
				(width 0.1)
				(type default)
			)
			(layer "F.Fab")
		)
		(fp_line
			(start 0.12065 -0.3048)
			(end 0.67945 -0.3048)
			(stroke
				(width 0.1)
				(type default)
			)
			(layer "F.Fab")
		)
		(fp_line
			(start 0.67945 -0.3048)
			(end 0.67945 0.3048)
			(stroke
				(width 0.1)
				(type default)
			)
			(layer "F.Fab")
		)
		(fp_line
			(start -0.67945 -0.305054)
			(end -0.12065 -0.305054)
			(stroke
				(width 0.1)
				(type default)
			)
			(layer "F.Fab")
		)
		(fp_line
			(start -0.12065 -0.305054)
			(end -0.12065 -0.2794)
			(stroke
				(width 0.1)
				(type default)
			)
			(layer "F.Fab")
		)
		(pad "1" smd circle
			(at -0.40005 0 270)
			(size 0 0)
			(layers "F.Cu" "F.Mask" "F.Paste")
			(net "GND")
		)
		(pad "2" smd circle
			(at 0.40005 0 270)
			(size 0 0)
			(layers "F.Cu" "F.Mask" "F.Paste")
			(net "PEX2_MODE_SEL6")
		)
	)
	(footprint ""
		(layer "F.Cu")
		(at 39.280592 -111.003334)
		(property "Reference" "C52"
			(at 0 0 0)
			(layer "F.SilkS")
			(hide yes)
			(effects
				(font
					(size 1.27 1.27)
				)
			)
		)
		(property "Value" ""
			(at 0 0 0)
			(layer "F.Fab")
			(effects
				(font
					(size 1.27 1.27)
				)
			)
		)
		(duplicate_pad_numbers_are_jumpers no)
		(fp_line
			(start -0.299974 -0.150114)
			(end 0.299974 -0.150114)
			(stroke
				(width 0.1)
				(type default)
			)
			(layer "F.Fab")
		)
		(fp_line
			(start -0.299974 0.150114)
			(end -0.299974 -0.150114)
			(stroke
				(width 0.1)
				(type default)
			)
			(layer "F.Fab")
		)
		(fp_line
			(start 0.299974 -0.150114)
			(end 0.299974 0.150114)
			(stroke
				(width 0.1)
				(type default)
			)
			(layer "F.Fab")
		)
		(fp_line
			(start 0.299974 0.150114)
			(end -0.299974 0.150114)
			(stroke
				(width 0.1)
				(type default)
			)
			(layer "F.Fab")
		)
		(pad "1" smd rect
			(at -0.2667 0)
			(size 0.3048 0.381)
			(layers "F.Cu" "F.Mask" "F.Paste")
			(net "P5E_PEX0_STN1_TX_DN<22>")
		)
		(pad "2" smd rect
			(at 0.2667 0)
			(size 0.3048 0.381)
			(layers "F.Cu" "F.Mask" "F.Paste")
			(net "P5E_PEX0_STN1_TX_C_DN<22>")
		)
	)
	(footprint ""
		(layer "F.Cu")
		(at 204.591158 -78.579472)
		(property "Reference" "R4336"
			(at 0 0 0)
			(layer "F.SilkS")
			(hide yes)
			(effects
				(font
					(size 1.27 1.27)
				)
			)
		)
		(property "Value" ""
			(at 0 0 0)
			(layer "F.Fab")
			(effects
				(font
					(size 1.27 1.27)
				)
			)
		)
		(duplicate_pad_numbers_are_jumpers no)
		(fp_line
			(start -0.7874 -0.4064)
			(end 0.7874 -0.4064)
			(stroke
				(width 0.1524)
				(type default)
			)
			(layer "F.SilkS")
		)
		(fp_line
			(start -0.7874 0.4064)
			(end -0.7874 -0.4064)
			(stroke
				(width 0.1524)
				(type default)
			)
			(layer "F.SilkS")
		)
		(fp_line
			(start 0.7874 -0.4064)
			(end 0.7874 0.4064)
			(stroke
				(width 0.1524)
				(type default)
			)
			(layer "F.SilkS")
		)
		(fp_line
			(start 0.7874 0.4064)
			(end -0.7874 0.4064)
			(stroke
				(width 0.1524)
				(type default)
			)
			(layer "F.SilkS")
		)
		(fp_line
			(start -0.67945 -0.305054)
			(end -0.12065 -0.305054)
			(stroke
				(width 0.1)
				(type default)
			)
			(layer "F.Fab")
		)
		(fp_line
			(start -0.67945 0.3048)
			(end -0.67945 -0.305054)
			(stroke
				(width 0.1)
				(type default)
			)
			(layer "F.Fab")
		)
		(fp_line
			(start -0.12065 -0.305054)
			(end -0.12065 -0.2794)
			(stroke
				(width 0.1)
				(type default)
			)
			(layer "F.Fab")
		)
		(fp_line
			(start -0.12065 -0.2794)
			(end 0.12065 -0.2794)
			(stroke
				(width 0.1)
				(type default)
			)
			(layer "F.Fab")
		)
		(fp_line
			(start -0.12065 0.2794)
			(end -0.12065 0.3048)
			(stroke
				(width 0.1)
				(type default)
			)
			(layer "F.Fab")
		)
		(fp_line
			(start -0.12065 0.3048)
			(end -0.67945 0.3048)
			(stroke
				(width 0.1)
				(type default)
			)
			(layer "F.Fab")
		)
		(fp_line
			(start 0.120396 0.2794)
			(end -0.12065 0.2794)
			(stroke
				(width 0.1)
				(type default)
			)
			(layer "F.Fab")
		)
		(fp_line
			(start 0.120396 0.3048)
			(end 0.120396 0.2794)
			(stroke
				(width 0.1)
				(type default)
			)
			(layer "F.Fab")
		)
		(fp_line
			(start 0.12065 -0.3048)
			(end 0.67945 -0.3048)
			(stroke
				(width 0.1)
				(type default)
			)
			(layer "F.Fab")
		)
		(fp_line
			(start 0.12065 -0.2794)
			(end 0.12065 -0.3048)
			(stroke
				(width 0.1)
				(type default)
			)
			(layer "F.Fab")
		)
		(fp_line
			(start 0.67945 -0.3048)
			(end 0.67945 0.3048)
			(stroke
				(width 0.1)
				(type default)
			)
			(layer "F.Fab")
		)
		(fp_line
			(start 0.67945 0.3048)
			(end 0.120396 0.3048)
			(stroke
				(width 0.1)
				(type default)
			)
			(layer "F.Fab")
		)
		(pad "1" smd circle
			(at -0.40005 0)
			(size 0 0)
			(layers "F.Cu" "F.Mask" "F.Paste")
			(net "P3V3_AUX")
		)
		(pad "2" smd circle
			(at 0.40005 0)
			(size 0 0)
			(layers "F.Cu" "F.Mask" "F.Paste")
			(net "SSD6_LED_R")
		)
	)
	(footprint ""
		(layer "F.Cu")
		(at 245.96471 -162.003994 90)
		(property "Reference" "PC813"
			(at 0 0 90)
			(layer "F.SilkS")
			(hide yes)
			(effects
				(font
					(size 1.27 1.27)
				)
			)
		)
		(property "Value" ""
			(at 0 0 90)
			(layer "F.Fab")
			(effects
				(font
					(size 1.27 1.27)
				)
			)
		)
		(duplicate_pad_numbers_are_jumpers no)
		(fp_line
			(start 0.7874 -0.4064)
			(end 0.7874 0.4064)
			(stroke
				(width 0.1524)
				(type default)
			)
			(layer "F.SilkS")
		)
		(fp_line
			(start -0.7874 -0.4064)
			(end 0.7874 -0.4064)
			(stroke
				(width 0.1524)
				(type default)
			)
			(layer "F.SilkS")
		)
		(fp_line
			(start 0.7874 0.4064)
			(end -0.7874 0.4064)
			(stroke
				(width 0.1524)
				(type default)
			)
			(layer "F.SilkS")
		)
		(fp_line
			(start -0.7874 0.4064)
			(end -0.7874 -0.4064)
			(stroke
				(width 0.1524)
				(type default)
			)
			(layer "F.SilkS")
		)
		(fp_line
			(start -0.12065 -0.305054)
			(end -0.12065 -0.2794)
			(stroke
				(width 0.1)
				(type default)
			)
			(layer "F.Fab")
		)
		(fp_line
			(start -0.67945 -0.305054)
			(end -0.12065 -0.305054)
			(stroke
				(width 0.1)
				(type default)
			)
			(layer "F.Fab")
		)
		(fp_line
			(start 0.67945 -0.3048)
			(end 0.67945 0.3048)
			(stroke
				(width 0.1)
				(type default)
			)
			(layer "F.Fab")
		)
		(fp_line
			(start 0.12065 -0.3048)
			(end 0.67945 -0.3048)
			(stroke
				(width 0.1)
				(type default)
			)
			(layer "F.Fab")
		)
		(fp_line
			(start 0.12065 -0.2794)
			(end 0.12065 -0.3048)
			(stroke
				(width 0.1)
				(type default)
			)
			(layer "F.Fab")
		)
		(fp_line
			(start -0.12065 -0.2794)
			(end 0.12065 -0.2794)
			(stroke
				(width 0.1)
				(type default)
			)
			(layer "F.Fab")
		)
		(fp_line
			(start 0.120396 0.2794)
			(end -0.12065 0.2794)
			(stroke
				(width 0.1)
				(type default)
			)
			(layer "F.Fab")
		)
		(fp_line
			(start -0.12065 0.2794)
			(end -0.12065 0.3048)
			(stroke
				(width 0.1)
				(type default)
			)
			(layer "F.Fab")
		)
		(fp_line
			(start 0.67945 0.3048)
			(end 0.120396 0.3048)
			(stroke
				(width 0.1)
				(type default)
			)
			(layer "F.Fab")
		)
		(fp_line
			(start 0.120396 0.3048)
			(end 0.120396 0.2794)
			(stroke
				(width 0.1)
				(type default)
			)
			(layer "F.Fab")
		)
		(fp_line
			(start -0.12065 0.3048)
			(end -0.67945 0.3048)
			(stroke
				(width 0.1)
				(type default)
			)
			(layer "F.Fab")
		)
		(fp_line
			(start -0.67945 0.3048)
			(end -0.67945 -0.305054)
			(stroke
				(width 0.1)
				(type default)
			)
			(layer "F.Fab")
		)
		(pad "1" smd circle
			(at -0.40005 0 90)
			(size 0 0)
			(layers "F.Cu" "F.Mask" "F.Paste")
			(net "P12V_NIC4_CO_TIMER")
		)
		(pad "2" smd circle
			(at 0.40005 0 90)
			(size 0 0)
			(layers "F.Cu" "F.Mask" "F.Paste")
			(net "GND")
		)
	)
	(footprint ""
		(layer "F.Cu")
		(at 223.498664 -207.02016 90)
		(property "Reference" "R5285"
			(at 0 0 90)
			(layer "F.SilkS")
			(hide yes)
			(effects
				(font
					(size 1.27 1.27)
				)
			)
		)
		(property "Value" ""
			(at 0 0 90)
			(layer "F.Fab")
			(effects
				(font
					(size 1.27 1.27)
				)
			)
		)
		(duplicate_pad_numbers_are_jumpers no)
		(fp_line
			(start 0.7874 -0.4064)
			(end 0.7874 0.4064)
			(stroke
				(width 0.1524)
				(type default)
			)
			(layer "F.SilkS")
		)
		(fp_line
			(start -0.7874 -0.4064)
			(end 0.7874 -0.4064)
			(stroke
				(width 0.1524)
				(type default)
			)
			(layer "F.SilkS")
		)
		(fp_line
			(start 0.7874 0.4064)
			(end -0.7874 0.4064)
			(stroke
				(width 0.1524)
				(type default)
			)
			(layer "F.SilkS")
		)
		(fp_line
			(start -0.7874 0.4064)
			(end -0.7874 -0.4064)
			(stroke
				(width 0.1524)
				(type default)
			)
			(layer "F.SilkS")
		)
		(fp_line
			(start -0.12065 -0.305054)
			(end -0.12065 -0.2794)
			(stroke
				(width 0.1)
				(type default)
			)
			(layer "F.Fab")
		)
		(fp_line
			(start -0.67945 -0.305054)
			(end -0.12065 -0.305054)
			(stroke
				(width 0.1)
				(type default)
			)
			(layer "F.Fab")
		)
		(fp_line
			(start 0.67945 -0.3048)
			(end 0.67945 0.3048)
			(stroke
				(width 0.1)
				(type default)
			)
			(layer "F.Fab")
		)
		(fp_line
			(start 0.12065 -0.3048)
			(end 0.67945 -0.3048)
			(stroke
				(width 0.1)
				(type default)
			)
			(layer "F.Fab")
		)
		(fp_line
			(start 0.12065 -0.2794)
			(end 0.12065 -0.3048)
			(stroke
				(width 0.1)
				(type default)
			)
			(layer "F.Fab")
		)
		(fp_line
			(start -0.12065 -0.2794)
			(end 0.12065 -0.2794)
			(stroke
				(width 0.1)
				(type default)
			)
			(layer "F.Fab")
		)
		(fp_line
			(start 0.120396 0.2794)
			(end -0.12065 0.2794)
			(stroke
				(width 0.1)
				(type default)
			)
			(layer "F.Fab")
		)
		(fp_line
			(start -0.12065 0.2794)
			(end -0.12065 0.3048)
			(stroke
				(width 0.1)
				(type default)
			)
			(layer "F.Fab")
		)
		(fp_line
			(start 0.67945 0.3048)
			(end 0.120396 0.3048)
			(stroke
				(width 0.1)
				(type default)
			)
			(layer "F.Fab")
		)
		(fp_line
			(start 0.120396 0.3048)
			(end 0.120396 0.2794)
			(stroke
				(width 0.1)
				(type default)
			)
			(layer "F.Fab")
		)
		(fp_line
			(start -0.12065 0.3048)
			(end -0.67945 0.3048)
			(stroke
				(width 0.1)
				(type default)
			)
			(layer "F.Fab")
		)
		(fp_line
			(start -0.67945 0.3048)
			(end -0.67945 -0.305054)
			(stroke
				(width 0.1)
				(type default)
			)
			(layer "F.Fab")
		)
		(pad "1" smd circle
			(at -0.40005 0 90)
			(size 0 0)
			(layers "F.Cu" "F.Mask" "F.Paste")
			(net "RST_SMB_SSD_R_N")
		)
		(pad "2" smd circle
			(at 0.40005 0 90)
			(size 0 0)
			(layers "F.Cu" "F.Mask" "F.Paste")
			(net "RST_SMB_SSD_N")
		)
	)
)
